# T6G (Grand Teton) — schematic netlist excerpt (pin names and nets, part order shuffled) for the footprints in the layout excerpt that follows; sources: Cadence DE-HDL packaged netlist, KiCad conversion of 04192023_DAF0TMB3IC0_F0TG_MB_C_brd_V02_OCP.brd

PC6802  Q_CAP  22UF 16V 20% X6S  pkg C0805  page 360 : A = SW_P12V_AUX_P1V8_RETIMER_CPU0_FLT ; B = GND
PR6629  Q_RES  5.6 1% CHIP  pkg 0402LF  page 365 : A = SW_P0V9_RETIMER_CPU1_BOOT2 ; B = SW_P0V9_RETIMER_CPU1_BOOT2_RC
R4452  Q_RES  10K 1% EMPTY  pkg 0402LF  page 176 : A = P3V3_AUX ; B = RST_USB_CPU0_HUB1_R_N

(kicad_pcb
	(version 20260206)
	(generator "pcbnew")
	(generator_version "10.0")
	(general
		(thickness 1.6)
		(legacy_teardrops no)
	)
	(paper "A4")
	(title_block
		(title "04192023_DAF0TMB3IC0_F0TG_MB_C_brd_V02_OCP.brd")
		(comment 1 "Grand Teton / footprints 3066-3068 of 8354")
	)
	(layers
		(0 "F.Cu" signal "TOP")
		(4 "In1.Cu" signal "GND")
		(6 "In2.Cu" signal "IN1")
		(8 "In3.Cu" signal "GND1")
		(10 "In4.Cu" signal "IN2")
		(12 "In5.Cu" signal "GND2")
		(14 "In6.Cu" signal "IN3")
		(16 "In7.Cu" signal "GND3")
		(18 "In8.Cu" signal "VCC")
		(20 "In9.Cu" signal "VCC1")
		(22 "In10.Cu" signal "GND4")
		(24 "In11.Cu" signal "IN4")
		(26 "In12.Cu" signal "GND5")
		(28 "In13.Cu" signal "IN5")
		(30 "In14.Cu" signal "GND6")
		(32 "In15.Cu" signal "IN6")
		(34 "In16.Cu" signal "GND7")
		(2 "B.Cu" signal "BOTTOM")
		(9 "F.Adhes" user "F.Adhesive")
		(11 "B.Adhes" user "B.Adhesive")
		(13 "F.Paste" user "Package Geometry/Pastemask Top")
		(15 "B.Paste" user "Package Geometry/Pastemask Bottom")
		(5 "F.SilkS" user "Ref Des/Silkscreen Top")
		(7 "B.SilkS" user "Ref Des/Silkscreen Bottom")
		(1 "F.Mask" user "Board Geometry/Soldermask Top")
		(3 "B.Mask" user "Board Geometry/Soldermask Bottom")
		(17 "Dwgs.User" user "User.Drawings")
		(19 "Cmts.User" user "User.Comments")
		(21 "Eco1.User" user "User.Eco1")
		(23 "Eco2.User" user "User.Eco2")
		(25 "Edge.Cuts" user "Board Geometry/Outline")
		(27 "Margin" user)
		(31 "F.CrtYd" user "Package Geometry/Place Bound Top")
		(29 "B.CrtYd" user "Package Geometry/Place Bound Bottom")
		(35 "F.Fab" user "Ref Des/Assembly Top")
		(33 "B.Fab" user "Ref Des/Assembly Bottom")
	)
	(footprint ""
		(layer "F.Cu")
		(at 26.545794 -393.317984 90)
		(property "Reference" "PR6629"
			(at 0 0 90)
			(layer "F.SilkS")
			(hide yes)
			(effects
				(font
					(size 1.27 1.27)
				)
			)
		)
		(property "Value" ""
			(at 0 0 90)
			(layer "F.Fab")
			(effects
				(font
					(size 1.27 1.27)
				)
			)
		)
		(duplicate_pad_numbers_are_jumpers no)
		(fp_line
			(start 0.7874 -0.4064)
			(end 0.7874 0.4064)
			(stroke
				(width 0.1524)
				(type default)
			)
			(layer "F.SilkS")
		)
		(fp_line
			(start -0.7874 -0.4064)
			(end 0.7874 -0.4064)
			(stroke
				(width 0.1524)
				(type default)
			)
			(layer "F.SilkS")
		)
		(fp_line
			(start 0.7874 0.4064)
			(end -0.7874 0.4064)
			(stroke
				(width 0.1524)
				(type default)
			)
			(layer "F.SilkS")
		)
		(fp_line
			(start -0.7874 0.4064)
			(end -0.7874 -0.4064)
			(stroke
				(width 0.1524)
				(type default)
			)
			(layer "F.SilkS")
		)
		(fp_line
			(start -0.12065 -0.305054)
			(end -0.12065 -0.2794)
			(stroke
				(width 0.1)
				(type default)
			)
			(layer "F.Fab")
		)
		(fp_line
			(start -0.67945 -0.305054)
			(end -0.12065 -0.305054)
			(stroke
				(width 0.1)
				(type default)
			)
			(layer "F.Fab")
		)
		(fp_line
			(start 0.67945 -0.3048)
			(end 0.67945 0.3048)
			(stroke
				(width 0.1)
				(type default)
			)
			(layer "F.Fab")
		)
		(fp_line
			(start 0.12065 -0.3048)
			(end 0.67945 -0.3048)
			(stroke
				(width 0.1)
				(type default)
			)
			(layer "F.Fab")
		)
		(fp_line
			(start 0.12065 -0.2794)
			(end 0.12065 -0.3048)
			(stroke
				(width 0.1)
				(type default)
			)
			(layer "F.Fab")
		)
		(fp_line
			(start -0.12065 -0.2794)
			(end 0.12065 -0.2794)
			(stroke
				(width 0.1)
				(type default)
			)
			(layer "F.Fab")
		)
		(fp_line
			(start 0.120396 0.2794)
			(end -0.12065 0.2794)
			(stroke
				(width 0.1)
				(type default)
			)
			(layer "F.Fab")
		)
		(fp_line
			(start -0.12065 0.2794)
			(end -0.12065 0.3048)
			(stroke
				(width 0.1)
				(type default)
			)
			(layer "F.Fab")
		)
		(fp_line
			(start 0.67945 0.3048)
			(end 0.120396 0.3048)
			(stroke
				(width 0.1)
				(type default)
			)
			(layer "F.Fab")
		)
		(fp_line
			(start 0.120396 0.3048)
			(end 0.120396 0.2794)
			(stroke
				(width 0.1)
				(type default)
			)
			(layer "F.Fab")
		)
		(fp_line
			(start -0.12065 0.3048)
			(end -0.67945 0.3048)
			(stroke
				(width 0.1)
				(type default)
			)
			(layer "F.Fab")
		)
		(fp_line
			(start -0.67945 0.3048)
			(end -0.67945 -0.305054)
			(stroke
				(width 0.1)
				(type default)
			)
			(layer "F.Fab")
		)
		(pad "1" smd circle
			(at -0.40005 0 90)
			(size 0 0)
			(layers "F.Cu" "F.Mask" "F.Paste")
			(net "SW_P0V9_RETIMER_CPU1_BOOT2")
		)
		(pad "2" smd circle
			(at 0.40005 0 90)
			(size 0 0)
			(layers "F.Cu" "F.Mask" "F.Paste")
			(net "SW_P0V9_RETIMER_CPU1_BOOT2_RC")
		)
	)
	(footprint ""
		(layer "F.Cu")
		(at 244.327426 -282.075636)
		(property "Reference" "PC6802"
			(at 0 0 0)
			(layer "F.SilkS")
			(hide yes)
			(effects
				(font
					(size 1.27 1.27)
				)
			)
		)
		(property "Value" ""
			(at 0 0 0)
			(layer "F.Fab")
			(effects
				(font
					(size 1.27 1.27)
				)
			)
		)
		(duplicate_pad_numbers_are_jumpers no)
		(fp_line
			(start -1.524 -0.762)
			(end 1.524 -0.762)
			(stroke
				(width 0.1524)
				(type default)
			)
			(layer "F.SilkS")
		)
		(fp_line
			(start -1.524 0.762)
			(end -1.524 -0.762)
			(stroke
				(width 0.1524)
				(type default)
			)
			(layer "F.SilkS")
		)
		(fp_line
			(start 1.524 -0.762)
			(end 1.524 0.762)
			(stroke
				(width 0.1524)
				(type default)
			)
			(layer "F.SilkS")
		)
		(fp_line
			(start 1.524 0.762)
			(end -1.524 0.762)
			(stroke
				(width 0.1524)
				(type default)
			)
			(layer "F.SilkS")
		)
		(fp_line
			(start -1.1049 -0.724916)
			(end -1.1049 0.724916)
			(stroke
				(width 0.1)
				(type default)
			)
			(layer "F.Fab")
		)
		(fp_line
			(start -1.1049 0.724916)
			(end 1.1049 0.724916)
			(stroke
				(width 0.1)
				(type default)
			)
			(layer "F.Fab")
		)
		(fp_line
			(start 1.1049 -0.724916)
			(end -1.1049 -0.724916)
			(stroke
				(width 0.1)
				(type default)
			)
			(layer "F.Fab")
		)
		(fp_line
			(start 1.1049 0.724916)
			(end 1.1049 -0.724916)
			(stroke
				(width 0.1)
				(type default)
			)
			(layer "F.Fab")
		)
		(pad "1" smd rect
			(at -0.889 0 180)
			(size 1.016 1.27)
			(layers "F.Cu" "F.Mask" "F.Paste")
			(net "SW_P12V_AUX_P1V8_RETIMER_CPU0_FLT")
		)
		(pad "2" smd rect
			(at 0.889 0 180)
			(size 1.016 1.27)
			(layers "F.Cu" "F.Mask" "F.Paste")
			(net "GND")
		)
	)
	(footprint ""
		(layer "F.Cu")
		(at 124.633228 -49.153064)
		(property "Reference" "R4452"
			(at 0 0 0)
			(layer "F.SilkS")
			(hide yes)
			(effects
				(font
					(size 1.27 1.27)
				)
			)
		)
		(property "Value" ""
			(at 0 0 0)
			(layer "F.Fab")
			(effects
				(font
					(size 1.27 1.27)
				)
			)
		)
		(duplicate_pad_numbers_are_jumpers no)
		(fp_line
			(start -0.7874 -0.4064)
			(end 0.7874 -0.4064)
			(stroke
				(width 0.1524)
				(type default)
			)
			(layer "F.SilkS")
		)
		(fp_line
			(start -0.7874 0.4064)
			(end -0.7874 -0.4064)
			(stroke
				(width 0.1524)
				(type default)
			)
			(layer "F.SilkS")
		)
		(fp_line
			(start 0.7874 -0.4064)
			(end 0.7874 0.4064)
			(stroke
				(width 0.1524)
				(type default)
			)
			(layer "F.SilkS")
		)
		(fp_line
			(start 0.7874 0.4064)
			(end -0.7874 0.4064)
			(stroke
				(width 0.1524)
				(type default)
			)
			(layer "F.SilkS")
		)
		(fp_line
			(start -0.67945 -0.305054)
			(end -0.12065 -0.305054)
			(stroke
				(width 0.1)
				(type default)
			)
			(layer "F.Fab")
		)
		(fp_line
			(start -0.67945 0.3048)
			(end -0.67945 -0.305054)
			(stroke
				(width 0.1)
				(type default)
			)
			(layer "F.Fab")
		)
		(fp_line
			(start -0.12065 -0.305054)
			(end -0.12065 -0.2794)
			(stroke
				(width 0.1)
				(type default)
			)
			(layer "F.Fab")
		)
		(fp_line
			(start -0.12065 -0.2794)
			(end 0.12065 -0.2794)
			(stroke
				(width 0.1)
				(type default)
			)
			(layer "F.Fab")
		)
		(fp_line
			(start -0.12065 0.2794)
			(end -0.12065 0.3048)
			(stroke
				(width 0.1)
				(type default)
			)
			(layer "F.Fab")
		)
		(fp_line
			(start -0.12065 0.3048)
			(end -0.67945 0.3048)
			(stroke
				(width 0.1)
				(type default)
			)
			(layer "F.Fab")
		)
		(fp_line
			(start 0.120396 0.2794)
			(end -0.12065 0.2794)
			(stroke
				(width 0.1)
				(type default)
			)
			(layer "F.Fab")
		)
		(fp_line
			(start 0.120396 0.3048)
			(end 0.120396 0.2794)
			(stroke
				(width 0.1)
				(type default)
			)
			(layer "F.Fab")
		)
		(fp_line
			(start 0.12065 -0.3048)
			(end 0.67945 -0.3048)
			(stroke
				(width 0.1)
				(type default)
			)
			(layer "F.Fab")
		)
		(fp_line
			(start 0.12065 -0.2794)
			(end 0.12065 -0.3048)
			(stroke
				(width 0.1)
				(type default)
			)
			(layer "F.Fab")
		)
		(fp_line
			(start 0.67945 -0.3048)
			(end 0.67945 0.3048)
			(stroke
				(width 0.1)
				(type default)
			)
			(layer "F.Fab")
		)
		(fp_line
			(start 0.67945 0.3048)
			(end 0.120396 0.3048)
			(stroke
				(width 0.1)
				(type default)
			)
			(layer "F.Fab")
		)
		(pad "1" smd circle
			(at -0.40005 0)
			(size 0 0)
			(layers "F.Cu" "F.Mask" "F.Paste")
			(net "P3V3_AUX")
		)
		(pad "2" smd circle
			(at 0.40005 0)
			(size 0 0)
			(layers "F.Cu" "F.Mask" "F.Paste")
			(net "RST_USB_CPU0_HUB1_R_N")
		)
	)
)
